# S9S_MB_2U (Grand Teton) — schematic netlist excerpt (pin names and nets, part order shuffled) for the footprints in the layout excerpt that follows; sources: Cadence DE-HDL packaged netlist, KiCad conversion of 03242023_DA0F0TMBIJ0_F0T_Motherboard_J_brd_V01_OCP.brd

R764  Q_RES  0 5% CHIP  pkg 0402LF  page 131 : A = JTAG_DBP_PRDY_N ; B = JTAG_DBP_PRDY_R1_N
PR273  Q_RES  0 5% CHIP  pkg 0402LF  page 292 : A = SH_PVCCINFAON_CPU1 ; B = SH_PVCCINFAON_CPU1_R

(kicad_pcb
	(version 20260206)
	(generator "pcbnew")
	(generator_version "10.0")
	(general
		(thickness 1.6)
		(legacy_teardrops no)
	)
	(paper "A4")
	(title_block
		(title "03242023_DA0F0TMBIJ0_F0T_Motherboard_J_brd_V01_OCP.brd")
		(comment 1 "Grand Teton / footprints 560-561 of 6105")
	)
	(layers
		(0 "F.Cu" signal "TOP")
		(4 "In1.Cu" signal "GND")
		(6 "In2.Cu" signal "IN1")
		(8 "In3.Cu" signal "GND1")
		(10 "In4.Cu" signal "IN2")
		(12 "In5.Cu" signal "GND2")
		(14 "In6.Cu" signal "IN3")
		(16 "In7.Cu" signal "GND3")
		(18 "In8.Cu" signal "VCC")
		(20 "In9.Cu" signal "VCC1")
		(22 "In10.Cu" signal "GND4")
		(24 "In11.Cu" signal "IN4")
		(26 "In12.Cu" signal "GND5")
		(28 "In13.Cu" signal "IN5")
		(30 "In14.Cu" signal "GND6")
		(32 "In15.Cu" signal "IN6")
		(34 "In16.Cu" signal "GND7")
		(2 "B.Cu" signal "BOTTOM")
		(9 "F.Adhes" user "F.Adhesive")
		(11 "B.Adhes" user "B.Adhesive")
		(13 "F.Paste" user "Package Geometry/Pastemask Top")
		(15 "B.Paste" user "Package Geometry/Pastemask Bottom")
		(5 "F.SilkS" user "Ref Des/Silkscreen Top")
		(7 "B.SilkS" user "Ref Des/Silkscreen Bottom")
		(1 "F.Mask" user "Board Geometry/Soldermask Top")
		(3 "B.Mask" user "Board Geometry/Soldermask Bottom")
		(17 "Dwgs.User" user "User.Drawings")
		(19 "Cmts.User" user "User.Comments")
		(21 "Eco1.User" user "User.Eco1")
		(23 "Eco2.User" user "User.Eco2")
		(25 "Edge.Cuts" user "Board Geometry/Outline")
		(27 "Margin" user)
		(31 "F.CrtYd" user "Package Geometry/Place Bound Top")
		(29 "B.CrtYd" user "Package Geometry/Place Bound Bottom")
		(35 "F.Fab" user "Ref Des/Assembly Top")
		(33 "B.Fab" user "Ref Des/Assembly Bottom")
	)
	(footprint ""
		(layer "F.Cu")
		(at 35.176206 -133.845046 -90)
		(property "Reference" "PR273"
			(at 0 0 270)
			(layer "F.SilkS")
			(hide yes)
			(effects
				(font
					(size 1.27 1.27)
				)
			)
		)
		(property "Value" ""
			(at 0 0 270)
			(layer "F.Fab")
			(effects
				(font
					(size 1.27 1.27)
				)
			)
		)
		(duplicate_pad_numbers_are_jumpers no)
		(fp_line
			(start -0.7874 0.4064)
			(end -0.7874 -0.4064)
			(stroke
				(width 0.1524)
				(type default)
			)
			(layer "F.SilkS")
		)
		(fp_line
			(start 0.7874 0.4064)
			(end -0.7874 0.4064)
			(stroke
				(width 0.1524)
				(type default)
			)
			(layer "F.SilkS")
		)
		(fp_line
			(start -0.7874 -0.4064)
			(end 0.7874 -0.4064)
			(stroke
				(width 0.1524)
				(type default)
			)
			(layer "F.SilkS")
		)
		(fp_line
			(start 0.7874 -0.4064)
			(end 0.7874 0.4064)
			(stroke
				(width 0.1524)
				(type default)
			)
			(layer "F.SilkS")
		)
		(fp_line
			(start -0.67945 0.3048)
			(end -0.67945 -0.305054)
			(stroke
				(width 0.1)
				(type default)
			)
			(layer "F.Fab")
		)
		(fp_line
			(start -0.12065 0.3048)
			(end -0.67945 0.3048)
			(stroke
				(width 0.1)
				(type default)
			)
			(layer "F.Fab")
		)
		(fp_line
			(start 0.120396 0.3048)
			(end 0.120396 0.2794)
			(stroke
				(width 0.1)
				(type default)
			)
			(layer "F.Fab")
		)
		(fp_line
			(start 0.67945 0.3048)
			(end 0.120396 0.3048)
			(stroke
				(width 0.1)
				(type default)
			)
			(layer "F.Fab")
		)
		(fp_line
			(start -0.12065 0.2794)
			(end -0.12065 0.3048)
			(stroke
				(width 0.1)
				(type default)
			)
			(layer "F.Fab")
		)
		(fp_line
			(start 0.120396 0.2794)
			(end -0.12065 0.2794)
			(stroke
				(width 0.1)
				(type default)
			)
			(layer "F.Fab")
		)
		(fp_line
			(start -0.12065 -0.2794)
			(end 0.12065 -0.2794)
			(stroke
				(width 0.1)
				(type default)
			)
			(layer "F.Fab")
		)
		(fp_line
			(start 0.12065 -0.2794)
			(end 0.12065 -0.3048)
			(stroke
				(width 0.1)
				(type default)
			)
			(layer "F.Fab")
		)
		(fp_line
			(start 0.12065 -0.3048)
			(end 0.67945 -0.3048)
			(stroke
				(width 0.1)
				(type default)
			)
			(layer "F.Fab")
		)
		(fp_line
			(start 0.67945 -0.3048)
			(end 0.67945 0.3048)
			(stroke
				(width 0.1)
				(type default)
			)
			(layer "F.Fab")
		)
		(fp_line
			(start -0.67945 -0.305054)
			(end -0.12065 -0.305054)
			(stroke
				(width 0.1)
				(type default)
			)
			(layer "F.Fab")
		)
		(fp_line
			(start -0.12065 -0.305054)
			(end -0.12065 -0.2794)
			(stroke
				(width 0.1)
				(type default)
			)
			(layer "F.Fab")
		)
		(pad "1" smd circle
			(at -0.40005 0 270)
			(size 0 0)
			(layers "F.Cu" "F.Mask" "F.Paste")
			(net "SH_PVCCINFAON_CPU1")
		)
		(pad "2" smd circle
			(at 0.40005 0 270)
			(size 0 0)
			(layers "F.Cu" "F.Mask" "F.Paste")
			(net "SH_PVCCINFAON_CPU1_R")
		)
	)
	(footprint ""
		(layer "F.Cu")
		(at 385.716272 -61.813948)
		(property "Reference" "R764"
			(at 0 0 0)
			(layer "F.SilkS")
			(hide yes)
			(effects
				(font
					(size 1.27 1.27)
				)
			)
		)
		(property "Value" ""
			(at 0 0 0)
			(layer "F.Fab")
			(effects
				(font
					(size 1.27 1.27)
				)
			)
		)
		(duplicate_pad_numbers_are_jumpers no)
		(fp_line
			(start -0.7874 -0.4064)
			(end 0.7874 -0.4064)
			(stroke
				(width 0.1524)
				(type default)
			)
			(layer "F.SilkS")
		)
		(fp_line
			(start -0.7874 0.4064)
			(end -0.7874 -0.4064)
			(stroke
				(width 0.1524)
				(type default)
			)
			(layer "F.SilkS")
		)
		(fp_line
			(start 0.7874 -0.4064)
			(end 0.7874 0.4064)
			(stroke
				(width 0.1524)
				(type default)
			)
			(layer "F.SilkS")
		)
		(fp_line
			(start 0.7874 0.4064)
			(end -0.7874 0.4064)
			(stroke
				(width 0.1524)
				(type default)
			)
			(layer "F.SilkS")
		)
		(fp_line
			(start -0.67945 -0.305054)
			(end -0.12065 -0.305054)
			(stroke
				(width 0.1)
				(type default)
			)
			(layer "F.Fab")
		)
		(fp_line
			(start -0.67945 0.3048)
			(end -0.67945 -0.305054)
			(stroke
				(width 0.1)
				(type default)
			)
			(layer "F.Fab")
		)
		(fp_line
			(start -0.12065 -0.305054)
			(end -0.12065 -0.2794)
			(stroke
				(width 0.1)
				(type default)
			)
			(layer "F.Fab")
		)
		(fp_line
			(start -0.12065 -0.2794)
			(end 0.12065 -0.2794)
			(stroke
				(width 0.1)
				(type default)
			)
			(layer "F.Fab")
		)
		(fp_line
			(start -0.12065 0.2794)
			(end -0.12065 0.3048)
			(stroke
				(width 0.1)
				(type default)
			)
			(layer "F.Fab")
		)
		(fp_line
			(start -0.12065 0.3048)
			(end -0.67945 0.3048)
			(stroke
				(width 0.1)
				(type default)
			)
			(layer "F.Fab")
		)
		(fp_line
			(start 0.120396 0.2794)
			(end -0.12065 0.2794)
			(stroke
				(width 0.1)
				(type default)
			)
			(layer "F.Fab")
		)
		(fp_line
			(start 0.120396 0.3048)
			(end 0.120396 0.2794)
			(stroke
				(width 0.1)
				(type default)
			)
			(layer "F.Fab")
		)
		(fp_line
			(start 0.12065 -0.3048)
			(end 0.67945 -0.3048)
			(stroke
				(width 0.1)
				(type default)
			)
			(layer "F.Fab")
		)
		(fp_line
			(start 0.12065 -0.2794)
			(end 0.12065 -0.3048)
			(stroke
				(width 0.1)
				(type default)
			)
			(layer "F.Fab")
		)
		(fp_line
			(start 0.67945 -0.3048)
			(end 0.67945 0.3048)
			(stroke
				(width 0.1)
				(type default)
			)
			(layer "F.Fab")
		)
		(fp_line
			(start 0.67945 0.3048)
			(end 0.120396 0.3048)
			(stroke
				(width 0.1)
				(type default)
			)
			(layer "F.Fab")
		)
		(pad "1" smd circle
			(at -0.40005 0)
			(size 0 0)
			(layers "F.Cu" "F.Mask" "F.Paste")
			(net "JTAG_DBP_PRDY_N")
		)
		(pad "2" smd circle
			(at 0.40005 0)
			(size 0 0)
			(layers "F.Cu" "F.Mask" "F.Paste")
			(net "JTAG_DBP_PRDY_R1_N")
		)
	)
)
